# SCM (Grand Teton) — schematic netlist excerpt (pin names and nets, part order shuffled) for the footprints in the layout excerpt that follows; sources: Cadence DE-HDL packaged netlist, KiCad conversion of 12092022_DA0F0TMDCD0_F0T_Management_Board_D_brd_V3_OCP.brd

R28  Q_RES  33.2 1% CHIP  pkg 0402LF  page 23 : A = V_BMC_LS_DDC_SCL ; B = V_BMC_LS_DDC_SCL_R
R296  Q_RES  100K 1% EMPTY  pkg 0402LF  page 28 : A = DEBUG_PORT_PRSNT_BUF_R_EN ; B = GND

(kicad_pcb
	(version 20260206)
	(generator "pcbnew")
	(generator_version "10.0")
	(general
		(thickness 1.6)
		(legacy_teardrops no)
	)
	(paper "A4")
	(title_block
		(title "12092022_DA0F0TMDCD0_F0T_Management_Board_D_brd_V3_OCP.brd")
		(comment 1 "Grand Teton / footprints 1417-1418 of 1440")
	)
	(layers
		(0 "F.Cu" signal "TOP")
		(4 "In1.Cu" signal "GND")
		(6 "In2.Cu" signal "IN1")
		(8 "In3.Cu" signal "GND1")
		(10 "In4.Cu" signal "IN2")
		(12 "In5.Cu" signal "VCC")
		(14 "In6.Cu" signal "VCC1")
		(16 "In7.Cu" signal "IN3")
		(18 "In8.Cu" signal "GND2")
		(20 "In9.Cu" signal "IN4")
		(22 "In10.Cu" signal "GND3")
		(2 "B.Cu" signal "BOTTOM")
		(9 "F.Adhes" user "F.Adhesive")
		(11 "B.Adhes" user "B.Adhesive")
		(13 "F.Paste" user "Package Geometry/Pastemask Top")
		(15 "B.Paste" user "Package Geometry/Pastemask Bottom")
		(5 "F.SilkS" user "Ref Des/Silkscreen Top")
		(7 "B.SilkS" user "Ref Des/Silkscreen Bottom")
		(1 "F.Mask" user "Board Geometry/Soldermask Top")
		(3 "B.Mask" user "Board Geometry/Soldermask Bottom")
		(17 "Dwgs.User" user "User.Drawings")
		(19 "Cmts.User" user "User.Comments")
		(21 "Eco1.User" user "User.Eco1")
		(23 "Eco2.User" user "User.Eco2")
		(25 "Edge.Cuts" user "Board Geometry/Outline")
		(27 "Margin" user)
		(31 "F.CrtYd" user "Package Geometry/Place Bound Top")
		(29 "B.CrtYd" user "Package Geometry/Place Bound Bottom")
		(35 "F.Fab" user "Ref Des/Assembly Top")
		(33 "B.Fab" user "Ref Des/Assembly Bottom")
	)
	(footprint ""
		(layer "B.Cu")
		(at 33.6296 -22.8346 -90)
		(property "Reference" "R28"
			(at 0 0 90)
			(layer "B.SilkS")
			(hide yes)
			(effects
				(font
					(size 1.27 1.27)
				)
				(justify mirror)
			)
		)
		(property "Value" ""
			(at 0 0 90)
			(layer "B.Fab")
			(effects
				(font
					(size 1.27 1.27)
				)
				(justify mirror)
			)
		)
		(duplicate_pad_numbers_are_jumpers no)
		(fp_line
			(start -0.7874 0.4064)
			(end 0.7874 0.4064)
			(stroke
				(width 0.1524)
				(type default)
			)
			(layer "B.SilkS")
		)
		(fp_line
			(start 0.7874 0.4064)
			(end 0.7874 -0.4064)
			(stroke
				(width 0.1524)
				(type default)
			)
			(layer "B.SilkS")
		)
		(fp_line
			(start -0.7874 -0.4064)
			(end -0.7874 0.4064)
			(stroke
				(width 0.1524)
				(type default)
			)
			(layer "B.SilkS")
		)
		(fp_line
			(start 0.7874 -0.4064)
			(end -0.7874 -0.4064)
			(stroke
				(width 0.1524)
				(type default)
			)
			(layer "B.SilkS")
		)
		(fp_line
			(start -0.67945 0.3048)
			(end -0.120396 0.3048)
			(stroke
				(width 0.1)
				(type default)
			)
			(layer "B.Fab")
		)
		(fp_line
			(start -0.120396 0.3048)
			(end -0.120396 0.2794)
			(stroke
				(width 0.1)
				(type default)
			)
			(layer "B.Fab")
		)
		(fp_line
			(start 0.12065 0.3048)
			(end 0.67945 0.3048)
			(stroke
				(width 0.1)
				(type default)
			)
			(layer "B.Fab")
		)
		(fp_line
			(start 0.67945 0.3048)
			(end 0.67945 -0.305054)
			(stroke
				(width 0.1)
				(type default)
			)
			(layer "B.Fab")
		)
		(fp_line
			(start -0.120396 0.2794)
			(end 0.12065 0.2794)
			(stroke
				(width 0.1)
				(type default)
			)
			(layer "B.Fab")
		)
		(fp_line
			(start 0.12065 0.2794)
			(end 0.12065 0.3048)
			(stroke
				(width 0.1)
				(type default)
			)
			(layer "B.Fab")
		)
		(fp_line
			(start -0.12065 -0.2794)
			(end -0.12065 -0.3048)
			(stroke
				(width 0.1)
				(type default)
			)
			(layer "B.Fab")
		)
		(fp_line
			(start 0.12065 -0.2794)
			(end -0.12065 -0.2794)
			(stroke
				(width 0.1)
				(type default)
			)
			(layer "B.Fab")
		)
		(fp_line
			(start -0.67945 -0.3048)
			(end -0.67945 0.3048)
			(stroke
				(width 0.1)
				(type default)
			)
			(layer "B.Fab")
		)
		(fp_line
			(start -0.12065 -0.3048)
			(end -0.67945 -0.3048)
			(stroke
				(width 0.1)
				(type default)
			)
			(layer "B.Fab")
		)
		(fp_line
			(start 0.12065 -0.305054)
			(end 0.12065 -0.2794)
			(stroke
				(width 0.1)
				(type default)
			)
			(layer "B.Fab")
		)
		(fp_line
			(start 0.67945 -0.305054)
			(end 0.12065 -0.305054)
			(stroke
				(width 0.1)
				(type default)
			)
			(layer "B.Fab")
		)
		(pad "1" smd circle
			(at 0.40005 0 90)
			(size 0 0)
			(layers "B.Cu" "B.Mask" "B.Paste")
			(net "V_BMC_LS_DDC_SCL")
		)
		(pad "2" smd circle
			(at -0.40005 0 90)
			(size 0 0)
			(layers "B.Cu" "B.Mask" "B.Paste")
			(net "V_BMC_LS_DDC_SCL_R")
		)
	)
	(footprint ""
		(layer "B.Cu")
		(at 48.00092 -24.11984 -90)
		(property "Reference" "R296"
			(at 0 0 90)
			(layer "B.SilkS")
			(hide yes)
			(effects
				(font
					(size 1.27 1.27)
				)
				(justify mirror)
			)
		)
		(property "Value" ""
			(at 0 0 90)
			(layer "B.Fab")
			(effects
				(font
					(size 1.27 1.27)
				)
				(justify mirror)
			)
		)
		(duplicate_pad_numbers_are_jumpers no)
		(fp_line
			(start -0.7874 0.4064)
			(end 0.7874 0.4064)
			(stroke
				(width 0.1524)
				(type default)
			)
			(layer "B.SilkS")
		)
		(fp_line
			(start 0.7874 0.4064)
			(end 0.7874 -0.4064)
			(stroke
				(width 0.1524)
				(type default)
			)
			(layer "B.SilkS")
		)
		(fp_line
			(start -0.7874 -0.4064)
			(end -0.7874 0.4064)
			(stroke
				(width 0.1524)
				(type default)
			)
			(layer "B.SilkS")
		)
		(fp_line
			(start 0.7874 -0.4064)
			(end -0.7874 -0.4064)
			(stroke
				(width 0.1524)
				(type default)
			)
			(layer "B.SilkS")
		)
		(fp_line
			(start -0.67945 0.3048)
			(end -0.120396 0.3048)
			(stroke
				(width 0.1)
				(type default)
			)
			(layer "B.Fab")
		)
		(fp_line
			(start -0.120396 0.3048)
			(end -0.120396 0.2794)
			(stroke
				(width 0.1)
				(type default)
			)
			(layer "B.Fab")
		)
		(fp_line
			(start 0.12065 0.3048)
			(end 0.67945 0.3048)
			(stroke
				(width 0.1)
				(type default)
			)
			(layer "B.Fab")
		)
		(fp_line
			(start 0.67945 0.3048)
			(end 0.67945 -0.305054)
			(stroke
				(width 0.1)
				(type default)
			)
			(layer "B.Fab")
		)
		(fp_line
			(start -0.120396 0.2794)
			(end 0.12065 0.2794)
			(stroke
				(width 0.1)
				(type default)
			)
			(layer "B.Fab")
		)
		(fp_line
			(start 0.12065 0.2794)
			(end 0.12065 0.3048)
			(stroke
				(width 0.1)
				(type default)
			)
			(layer "B.Fab")
		)
		(fp_line
			(start -0.12065 -0.2794)
			(end -0.12065 -0.3048)
			(stroke
				(width 0.1)
				(type default)
			)
			(layer "B.Fab")
		)
		(fp_line
			(start 0.12065 -0.2794)
			(end -0.12065 -0.2794)
			(stroke
				(width 0.1)
				(type default)
			)
			(layer "B.Fab")
		)
		(fp_line
			(start -0.67945 -0.3048)
			(end -0.67945 0.3048)
			(stroke
				(width 0.1)
				(type default)
			)
			(layer "B.Fab")
		)
		(fp_line
			(start -0.12065 -0.3048)
			(end -0.67945 -0.3048)
			(stroke
				(width 0.1)
				(type default)
			)
			(layer "B.Fab")
		)
		(fp_line
			(start 0.12065 -0.305054)
			(end 0.12065 -0.2794)
			(stroke
				(width 0.1)
				(type default)
			)
			(layer "B.Fab")
		)
		(fp_line
			(start 0.67945 -0.305054)
			(end 0.12065 -0.305054)
			(stroke
				(width 0.1)
				(type default)
			)
			(layer "B.Fab")
		)
		(pad "1" smd circle
			(at 0.40005 0 90)
			(size 0 0)
			(layers "B.Cu" "B.Mask" "B.Paste")
			(net "DEBUG_PORT_PRSNT_BUF_R_EN")
		)
		(pad "2" smd circle
			(at -0.40005 0 90)
			(size 0 0)
			(layers "B.Cu" "B.Mask" "B.Paste")
			(net "GND")
		)
	)
)
